(kicad_pcb
	(version 20260206)
	(generator "pcbnew")
	(generator_version "10.0")
	(general
		(thickness 1.6)
		(legacy_teardrops no)
	)
	(paper "A4")
	(title_block
		(title "panther-plus-userver — 13130-1b_20150205.brd")
		(comment 1 "Honey Badger (Wiwynn) / footprints 849-855 of 1509")
	)
	(layers
		(0 "F.Cu" signal "TOP")
		(4 "In1.Cu" signal "L2")
		(6 "In2.Cu" signal "L3")
		(8 "In3.Cu" signal "L4")
		(10 "In4.Cu" signal "L5")
		(12 "In5.Cu" signal "L6")
		(14 "In6.Cu" signal "L7")
		(16 "In7.Cu" signal "L8")
		(18 "In8.Cu" signal "L9")
		(20 "In9.Cu" signal "L10")
		(22 "In10.Cu" signal "L11")
		(2 "B.Cu" signal "BOTTOM")
		(9 "F.Adhes" user "F.Adhesive")
		(11 "B.Adhes" user "B.Adhesive")
		(13 "F.Paste" user "Package Geometry/Pastemask Top")
		(15 "B.Paste" user "Package Geometry/Pastemask Bottom")
		(5 "F.SilkS" user "Ref Des/Silkscreen Top")
		(7 "B.SilkS" user "Ref Des/Silkscreen Bottom")
		(1 "F.Mask" user "Board Geometry/Soldermask Top")
		(3 "B.Mask" user "Board Geometry/Soldermask Bottom")
		(17 "Dwgs.User" user "User.Drawings")
		(19 "Cmts.User" user "User.Comments")
		(21 "Eco1.User" user "User.Eco1")
		(23 "Eco2.User" user "User.Eco2")
		(25 "Edge.Cuts" user "Board Geometry/Outline")
		(27 "Margin" user)
		(31 "F.CrtYd" user "Package Geometry/Place Bound Top")
		(29 "B.CrtYd" user "Package Geometry/Place Bound Bottom")
		(35 "F.Fab" user "Ref Des/Assembly Top")
		(33 "B.Fab" user "Ref Des/Assembly Bottom")
	)
	(footprint ""
		(layer "B.Cu")
		(at 80.264 -13.462)
		(property "Reference" "C275"
			(at 0 0 0)
			(layer "B.SilkS")
			(hide yes)
			(effects
				(font
					(size 1.27 1.27)
				)
				(justify mirror)
			)
		)
		(property "Value" "SCD1U16V2KX-3GP"
			(at -1.1811 -2.7051 0)
			(unlocked yes)
			(layer "B.Fab")
			(hide yes)
			(effects
				(font
					(size 1.016 1.016)
					(thickness 0.1524)
				)
				(justify mirror)
			)
		)
		(property "Device Type" "C402H22"
			(at -1.1811 -4.2291 0)
			(unlocked yes)
			(layer "B.Fab")
			(hide yes)
			(effects
				(font
					(size 1.016 1.016)
					(thickness 0.1524)
				)
				(justify mirror)
			)
		)
		(duplicate_pad_numbers_are_jumpers no)
		(fp_rect
			(start 0.381 0.7366)
			(end -0.381 -0.7366)
			(stroke
				(width 0)
				(type default)
			)
			(fill no)
			(layer "B.CrtYd")
		)
		(fp_rect
			(start 0.381 0.7366)
			(end -0.381 -0.7366)
			(stroke
				(width 0)
				(type default)
			)
			(fill no)
			(layer "B.Fab")
		)
		(pad "1" smd custom
			(at 0 -0.4572 180)
			(size 0.1143 0.1143)
			(layers "B.Cu" "B.Mask" "B.Paste")
			(net "P2E_CPU_SAS_C_TX_DN0")
			(options
				(clearance outline)
				(anchor circle)
			)
			(primitives
				(gr_poly
					(pts
						(arc
							(start -0.254 0.1778)
							(mid -0.239121 0.213721)
							(end -0.2032 0.2286)
						)
						(arc
							(start 0.2032 0.2286)
							(mid 0.239121 0.213721)
							(end 0.254 0.1778)
						)
						(arc
							(start 0.254 -0.1778)
							(mid 0.239121 -0.213721)
							(end 0.2032 -0.2286)
						)
						(arc
							(start -0.2032 -0.2286)
							(mid -0.239121 -0.213721)
							(end -0.254 -0.1778)
						)
					)
					(width 0)
					(fill yes)
				)
			)
		)
		(pad "2" smd custom
			(at 0 0.4572 180)
			(size 0.1143 0.1143)
			(layers "B.Cu" "B.Mask" "B.Paste")
			(net "P2E_CPU_SAS_TX_DN0")
			(options
				(clearance outline)
				(anchor circle)
			)
			(primitives
				(gr_poly
					(pts
						(arc
							(start -0.254 0.1778)
							(mid -0.239121 0.213721)
							(end -0.2032 0.2286)
						)
						(arc
							(start 0.2032 0.2286)
							(mid 0.239121 0.213721)
							(end 0.254 0.1778)
						)
						(arc
							(start 0.254 -0.1778)
							(mid 0.239121 -0.213721)
							(end 0.2032 -0.2286)
						)
						(arc
							(start -0.2032 -0.2286)
							(mid -0.239121 -0.213721)
							(end -0.254 -0.1778)
						)
					)
					(width 0)
					(fill yes)
				)
			)
		)
	)
	(footprint ""
		(layer "B.Cu")
		(at 157.988 -12.574778 180)
		(property "Reference" "C298"
			(at 0 0 0)
			(layer "B.SilkS")
			(hide yes)
			(effects
				(font
					(size 1.27 1.27)
				)
				(justify mirror)
			)
		)
		(property "Value" "SC10U6D3V3MX-GP"
			(at 0.0254 -2.0193 180)
			(unlocked yes)
			(layer "B.Fab")
			(hide yes)
			(effects
				(font
					(size 1.016 1.016)
					(thickness 0.1524)
				)
				(justify mirror)
			)
		)
		(property "Device Type" "C603H38"
			(at 0.0254 -3.5433 180)
			(unlocked yes)
			(layer "B.Fab")
			(hide yes)
			(effects
				(font
					(size 1.016 1.016)
					(thickness 0.1524)
				)
				(justify mirror)
			)
		)
		(duplicate_pad_numbers_are_jumpers no)
		(fp_line
			(start 0.4064 0)
			(end -0.4064 0)
			(stroke
				(width 0.2286)
				(type default)
			)
			(layer "B.SilkS")
		)
		(fp_rect
			(start 0.635 1.1811)
			(end -0.635 -1.1811)
			(stroke
				(width 0)
				(type default)
			)
			(fill no)
			(layer "B.CrtYd")
		)
		(fp_rect
			(start 0.635 1.1811)
			(end -0.635 -1.1811)
			(stroke
				(width 0)
				(type default)
			)
			(fill no)
			(layer "B.Fab")
		)
		(pad "1" smd custom
			(at 0 -0.6604)
			(size 0.19685 0.19685)
			(layers "B.Cu" "B.Mask" "B.Paste")
			(net "PV_VDDR")
			(options
				(clearance outline)
				(anchor circle)
			)
			(primitives
				(gr_poly
					(pts
						(arc
							(start 0.508 0.2921)
							(mid 0.478242 0.363942)
							(end 0.4064 0.3937)
						)
						(arc
							(start -0.4064 0.3937)
							(mid -0.478242 0.363942)
							(end -0.508 0.2921)
						)
						(arc
							(start -0.508 -0.2921)
							(mid -0.478242 -0.363942)
							(end -0.4064 -0.3937)
						)
						(arc
							(start 0.4064 -0.3937)
							(mid 0.478242 -0.363942)
							(end 0.508 -0.2921)
						)
					)
					(width 0)
					(fill yes)
				)
			)
		)
		(pad "2" smd custom
			(at 0 0.6604)
			(size 0.19685 0.19685)
			(layers "B.Cu" "B.Mask" "B.Paste")
			(net "GND")
			(options
				(clearance outline)
				(anchor circle)
			)
			(primitives
				(gr_poly
					(pts
						(arc
							(start 0.508 0.2921)
							(mid 0.478242 0.363942)
							(end 0.4064 0.3937)
						)
						(arc
							(start -0.4064 0.3937)
							(mid -0.478242 0.363942)
							(end -0.508 0.2921)
						)
						(arc
							(start -0.508 -0.2921)
							(mid -0.478242 -0.363942)
							(end -0.4064 -0.3937)
						)
						(arc
							(start 0.4064 -0.3937)
							(mid 0.478242 -0.363942)
							(end 0.508 -0.2921)
						)
					)
					(width 0)
					(fill yes)
				)
			)
		)
	)
	(footprint ""
		(layer "B.Cu")
		(at 70.485 -53.467)
		(property "Reference" "R275"
			(at 0 0 0)
			(layer "B.SilkS")
			(hide yes)
			(effects
				(font
					(size 1.27 1.27)
				)
				(justify mirror)
			)
		)
		(property "Value" "1KR2F-3-GP"
			(at -0.064008 -3.993896 0)
			(unlocked yes)
			(layer "B.Fab")
			(hide yes)
			(effects
				(font
					(size 1.016 1.016)
					(thickness 0.1524)
				)
				(justify mirror)
			)
		)
		(property "Device Type" "R402H16"
			(at -0.064008 -5.517896 0)
			(unlocked yes)
			(layer "B.Fab")
			(hide yes)
			(effects
				(font
					(size 1.016 1.016)
					(thickness 0.1524)
				)
				(justify mirror)
			)
		)
		(duplicate_pad_numbers_are_jumpers no)
		(fp_rect
			(start 0.381 0.8382)
			(end -0.381 -0.8382)
			(stroke
				(width 0)
				(type default)
			)
			(fill no)
			(layer "B.CrtYd")
		)
		(fp_rect
			(start 0.381 0.8382)
			(end -0.381 -0.8382)
			(stroke
				(width 0)
				(type default)
			)
			(fill no)
			(layer "B.Fab")
		)
		(pad "1" smd custom
			(at 0 -0.4318 180)
			(size 0.127 0.127)
			(layers "B.Cu" "B.Mask" "B.Paste")
			(net "P3V3_STBY")
			(options
				(clearance outline)
				(anchor circle)
			)
			(primitives
				(gr_poly
					(pts
						(arc
							(start -0.2032 0.2794)
							(mid -0.239121 0.264521)
							(end -0.254 0.2286)
						)
						(arc
							(start -0.254 -0.2286)
							(mid -0.239121 -0.264521)
							(end -0.2032 -0.2794)
						)
						(arc
							(start 0.2032 -0.2794)
							(mid 0.239121 -0.264521)
							(end 0.254 -0.2286)
						)
						(arc
							(start 0.254 0.2286)
							(mid 0.239121 0.264521)
							(end 0.2032 0.2794)
						)
					)
					(width 0)
					(fill yes)
				)
			)
		)
		(pad "2" smd custom
			(at 0 0.4318 180)
			(size 0.127 0.127)
			(layers "B.Cu" "B.Mask" "B.Paste")
			(net "MEMORY_HOT_LV_R#")
			(options
				(clearance outline)
				(anchor circle)
			)
			(primitives
				(gr_poly
					(pts
						(arc
							(start -0.2032 0.2794)
							(mid -0.239121 0.264521)
							(end -0.254 0.2286)
						)
						(arc
							(start -0.254 -0.2286)
							(mid -0.239121 -0.264521)
							(end -0.2032 -0.2794)
						)
						(arc
							(start 0.2032 -0.2794)
							(mid 0.239121 -0.264521)
							(end 0.254 -0.2286)
						)
						(arc
							(start 0.254 0.2286)
							(mid 0.239121 0.264521)
							(end 0.2032 0.2794)
						)
					)
					(width 0)
					(fill yes)
				)
			)
		)
	)
	(footprint ""
		(layer "B.Cu")
		(at 74.041 -29.464 90)
		(property "Reference" "R457"
			(at 0 0 90)
			(layer "B.SilkS")
			(hide yes)
			(effects
				(font
					(size 1.27 1.27)
				)
				(justify mirror)
			)
		)
		(property "Value" "10KR2F-2-GP"
			(at -1.7907 -1.1176 90)
			(unlocked yes)
			(layer "B.Fab")
			(hide yes)
			(effects
				(font
					(size 1.016 1.016)
					(thickness 0.1524)
				)
				(justify mirror)
			)
		)
		(property "Device Type" "R402H16"
			(at -1.7907 -2.6416 90)
			(unlocked yes)
			(layer "B.Fab")
			(hide yes)
			(effects
				(font
					(size 1.016 1.016)
					(thickness 0.1524)
				)
				(justify mirror)
			)
		)
		(duplicate_pad_numbers_are_jumpers no)
		(fp_rect
			(start 0.381 0.8382)
			(end -0.381 -0.8382)
			(stroke
				(width 0)
				(type default)
			)
			(fill no)
			(layer "B.CrtYd")
		)
		(fp_rect
			(start 0.381 0.8382)
			(end -0.381 -0.8382)
			(stroke
				(width 0)
				(type default)
			)
			(fill no)
			(layer "B.Fab")
		)
		(pad "1" smd custom
			(at 0 -0.4318 270)
			(size 0.127 0.127)
			(layers "B.Cu" "B.Mask" "B.Paste")
			(net "P3V3_CPU")
			(options
				(clearance outline)
				(anchor circle)
			)
			(primitives
				(gr_poly
					(pts
						(arc
							(start -0.2032 0.2794)
							(mid -0.239121 0.264521)
							(end -0.254 0.2286)
						)
						(arc
							(start -0.254 -0.2286)
							(mid -0.239121 -0.264521)
							(end -0.2032 -0.2794)
						)
						(arc
							(start 0.2032 -0.2794)
							(mid 0.239121 -0.264521)
							(end 0.254 -0.2286)
						)
						(arc
							(start 0.254 0.2286)
							(mid 0.239121 0.264521)
							(end 0.2032 0.2794)
						)
					)
					(width 0)
					(fill yes)
				)
			)
		)
		(pad "2" smd custom
			(at 0 0.4318 270)
			(size 0.127 0.127)
			(layers "B.Cu" "B.Mask" "B.Paste")
			(net "REV_CPU_FPGA_IO0")
			(options
				(clearance outline)
				(anchor circle)
			)
			(primitives
				(gr_poly
					(pts
						(arc
							(start -0.2032 0.2794)
							(mid -0.239121 0.264521)
							(end -0.254 0.2286)
						)
						(arc
							(start -0.254 -0.2286)
							(mid -0.239121 -0.264521)
							(end -0.2032 -0.2794)
						)
						(arc
							(start 0.2032 -0.2794)
							(mid 0.239121 -0.264521)
							(end 0.254 -0.2286)
						)
						(arc
							(start 0.254 0.2286)
							(mid 0.239121 0.264521)
							(end 0.2032 0.2794)
						)
					)
					(width 0)
					(fill yes)
				)
			)
		)
	)
	(footprint ""
		(layer "B.Cu")
		(at 69.088 -43.815)
		(property "Reference" "Q14"
			(at 0 0 0)
			(layer "B.SilkS")
			(hide yes)
			(effects
				(font
					(size 1.27 1.27)
				)
				(justify mirror)
			)
		)
		(property "Value" "2N7002A-7-GP"
			(at 4.3561 -5.7912 0)
			(unlocked yes)
			(layer "B.Fab")
			(hide yes)
			(effects
				(font
					(size 1.016 1.016)
					(thickness 0.1524)
				)
				(justify mirror)
			)
		)
		(property "Device Type" "SOT23DGS2D4H48"
			(at 4.3561 -7.3152 0)
			(unlocked yes)
			(layer "B.Fab")
			(hide yes)
			(effects
				(font
					(size 1.016 1.016)
					(thickness 0.1524)
				)
				(justify mirror)
			)
		)
		(duplicate_pad_numbers_are_jumpers no)
		(fp_line
			(start -1.7145 -0.4445)
			(end 1.7145 -0.4445)
			(stroke
				(width 0.1524)
				(type default)
			)
			(layer "B.SilkS")
		)
		(fp_line
			(start -1.7145 0.4445)
			(end -1.7145 -0.4445)
			(stroke
				(width 0.1524)
				(type default)
			)
			(layer "B.SilkS")
		)
		(fp_line
			(start 1.7145 -0.4445)
			(end 1.7145 0.4445)
			(stroke
				(width 0.1524)
				(type default)
			)
			(layer "B.SilkS")
		)
		(fp_line
			(start 1.7145 0.4445)
			(end -1.7145 0.4445)
			(stroke
				(width 0.1524)
				(type default)
			)
			(layer "B.SilkS")
		)
		(fp_poly
			(pts
				(xy 1.4224 1.5621) (xy 1.4224 0.9017) (xy 1.7145 0.9017) (xy 1.7145 -0.9017) (xy 0.4699 -0.9017)
				(xy 0.4699 -1.5621) (xy -0.4699 -1.5621) (xy -0.4699 -0.9017) (xy -1.7145 -0.9017) (xy -1.7145 0.9017)
				(xy -1.4224 0.9017) (xy -1.4224 1.5621) (xy -0.4826 1.5621) (xy -0.4826 0.9017) (xy 0.4826 0.9017)
				(xy 0.4826 1.5621)
			)
			(stroke
				(width 0)
				(type default)
			)
			(fill no)
			(layer "B.CrtYd")
		)
		(fp_poly
			(pts
				(xy 1.4224 1.5621) (xy 1.4224 0.9017) (xy 1.7145 0.9017) (xy 1.7145 -0.9017) (xy 0.4699 -0.9017)
				(xy 0.4699 -1.5621) (xy -0.4699 -1.5621) (xy -0.4699 -0.9017) (xy -1.7145 -0.9017) (xy -1.7145 0.9017)
				(xy -1.4224 0.9017) (xy -1.4224 1.5621) (xy -0.4826 1.5621) (xy -0.4826 0.9017) (xy 0.4826 0.9017)
				(xy 0.4826 1.5621)
			)
			(stroke
				(width 0)
				(type default)
			)
			(fill no)
			(layer "B.Fab")
		)
		(pad "D" smd custom
			(at 0 -1.069086 180)
			(size 0.17145 0.17145)
			(layers "B.Cu" "B.Mask" "B.Paste")
			(net "CPU_DIAG_LED_D")
			(options
				(clearance outline)
				(anchor circle)
			)
			(primitives
				(gr_poly
					(pts
						(arc
							(start -0.1397 -0.3683)
							(mid -0.283384 -0.308784)
							(end -0.3429 -0.1651)
						)
						(arc
							(start -0.3429 0.1651)
							(mid -0.283384 0.308784)
							(end -0.1397 0.3683)
						)
						(arc
							(start 0.1397 0.3683)
							(mid 0.283384 0.308784)
							(end 0.3429 0.1651)
						)
						(arc
							(start 0.3429 -0.1651)
							(mid 0.283384 -0.308784)
							(end 0.1397 -0.3683)
						)
					)
					(width 0)
					(fill yes)
				)
			)
		)
		(pad "G" smd custom
			(at 0.94996 1.069086 180)
			(size 0.17145 0.17145)
			(layers "B.Cu" "B.Mask" "B.Paste")
			(net "CPU_DIAG_LED_R")
			(options
				(clearance outline)
				(anchor circle)
			)
			(primitives
				(gr_poly
					(pts
						(arc
							(start -0.1397 -0.3683)
							(mid -0.283384 -0.308784)
							(end -0.3429 -0.1651)
						)
						(arc
							(start -0.3429 0.1651)
							(mid -0.283384 0.308784)
							(end -0.1397 0.3683)
						)
						(arc
							(start 0.1397 0.3683)
							(mid 0.283384 0.308784)
							(end 0.3429 0.1651)
						)
						(arc
							(start 0.3429 -0.1651)
							(mid 0.283384 -0.308784)
							(end 0.1397 -0.3683)
						)
					)
					(width 0)
					(fill yes)
				)
			)
		)
		(pad "S" smd custom
			(at -0.94996 1.069086 180)
			(size 0.17145 0.17145)
			(layers "B.Cu" "B.Mask" "B.Paste")
			(net "GND")
			(options
				(clearance outline)
				(anchor circle)
			)
			(primitives
				(gr_poly
					(pts
						(arc
							(start -0.1397 -0.3683)
							(mid -0.283384 -0.308784)
							(end -0.3429 -0.1651)
						)
						(arc
							(start -0.3429 0.1651)
							(mid -0.283384 0.308784)
							(end -0.1397 0.3683)
						)
						(arc
							(start 0.1397 0.3683)
							(mid 0.283384 0.308784)
							(end 0.3429 0.1651)
						)
						(arc
							(start 0.3429 -0.1651)
							(mid 0.283384 -0.308784)
							(end 0.1397 -0.3683)
						)
					)
					(width 0)
					(fill yes)
				)
			)
		)
	)
	(footprint ""
		(layer "B.Cu")
		(at 45.212 -42.164)
		(property "Reference" "C41"
			(at 0 0 0)
			(layer "B.SilkS")
			(hide yes)
			(effects
				(font
					(size 1.27 1.27)
				)
				(justify mirror)
			)
		)
		(property "Value" "SCD1U10V2KX-5GP"
			(at -1.1811 -2.7051 0)
			(unlocked yes)
			(layer "B.Fab")
			(hide yes)
			(effects
				(font
					(size 1.016 1.016)
					(thickness 0.1524)
				)
				(justify mirror)
			)
		)
		(property "Device Type" "C402H22"
			(at -1.1811 -4.2291 0)
			(unlocked yes)
			(layer "B.Fab")
			(hide yes)
			(effects
				(font
					(size 1.016 1.016)
					(thickness 0.1524)
				)
				(justify mirror)
			)
		)
		(duplicate_pad_numbers_are_jumpers no)
		(fp_rect
			(start 0.381 0.7366)
			(end -0.381 -0.7366)
			(stroke
				(width 0)
				(type default)
			)
			(fill no)
			(layer "B.CrtYd")
		)
		(fp_rect
			(start 0.381 0.7366)
			(end -0.381 -0.7366)
			(stroke
				(width 0)
				(type default)
			)
			(fill no)
			(layer "B.Fab")
		)
		(pad "1" smd custom
			(at 0 -0.4572 180)
			(size 0.1143 0.1143)
			(layers "B.Cu" "B.Mask" "B.Paste")
			(net "P1V5_CLK_VDDDIF")
			(options
				(clearance outline)
				(anchor circle)
			)
			(primitives
				(gr_poly
					(pts
						(arc
							(start -0.254 0.1778)
							(mid -0.239121 0.213721)
							(end -0.2032 0.2286)
						)
						(arc
							(start 0.2032 0.2286)
							(mid 0.239121 0.213721)
							(end 0.254 0.1778)
						)
						(arc
							(start 0.254 -0.1778)
							(mid 0.239121 -0.213721)
							(end 0.2032 -0.2286)
						)
						(arc
							(start -0.2032 -0.2286)
							(mid -0.239121 -0.213721)
							(end -0.254 -0.1778)
						)
					)
					(width 0)
					(fill yes)
				)
			)
		)
		(pad "2" smd custom
			(at 0 0.4572 180)
			(size 0.1143 0.1143)
			(layers "B.Cu" "B.Mask" "B.Paste")
			(net "GND")
			(options
				(clearance outline)
				(anchor circle)
			)
			(primitives
				(gr_poly
					(pts
						(arc
							(start -0.254 0.1778)
							(mid -0.239121 0.213721)
							(end -0.2032 0.2286)
						)
						(arc
							(start 0.2032 0.2286)
							(mid 0.239121 0.213721)
							(end 0.254 0.1778)
						)
						(arc
							(start 0.254 -0.1778)
							(mid 0.239121 -0.213721)
							(end 0.2032 -0.2286)
						)
						(arc
							(start -0.2032 -0.2286)
							(mid -0.239121 -0.213721)
							(end -0.254 -0.1778)
						)
					)
					(width 0)
					(fill yes)
				)
			)
		)
	)
	(footprint ""
		(layer "B.Cu")
		(at 154.559 -53.594 -90)
		(property "Reference" "C358"
			(at 0 0 90)
			(layer "B.SilkS")
			(hide yes)
			(effects
				(font
					(size 1.27 1.27)
				)
				(justify mirror)
			)
		)
		(property "Value" "SCD1U16V2KX-3GP"
			(at -1.8923 -1.2065 270)
			(unlocked yes)
			(layer "B.Fab")
			(hide yes)
			(effects
				(font
					(size 1.016 1.016)
					(thickness 0.1524)
				)
				(justify mirror)
			)
		)
		(property "Device Type" "C402H22"
			(at -1.8923 -2.7305 270)
			(unlocked yes)
			(layer "B.Fab")
			(hide yes)
			(effects
				(font
					(size 1.016 1.016)
					(thickness 0.1524)
				)
				(justify mirror)
			)
		)
		(duplicate_pad_numbers_are_jumpers no)
		(fp_rect
			(start 0.381 0.7366)
			(end -0.381 -0.7366)
			(stroke
				(width 0)
				(type default)
			)
			(fill no)
			(layer "B.CrtYd")
		)
		(fp_rect
			(start 0.381 0.7366)
			(end -0.381 -0.7366)
			(stroke
				(width 0)
				(type default)
			)
			(fill no)
			(layer "B.Fab")
		)
		(pad "1" smd custom
			(at 0 -0.4572 90)
			(size 0.1143 0.1143)
			(layers "B.Cu" "B.Mask" "B.Paste")
			(net "P3V3_STBY")
			(options
				(clearance outline)
				(anchor circle)
			)
			(primitives
				(gr_poly
					(pts
						(arc
							(start -0.254 0.1778)
							(mid -0.239121 0.213721)
							(end -0.2032 0.2286)
						)
						(arc
							(start 0.2032 0.2286)
							(mid 0.239121 0.213721)
							(end 0.254 0.1778)
						)
						(arc
							(start 0.254 -0.1778)
							(mid 0.239121 -0.213721)
							(end 0.2032 -0.2286)
						)
						(arc
							(start -0.2032 -0.2286)
							(mid -0.239121 -0.213721)
							(end -0.254 -0.1778)
						)
					)
					(width 0)
					(fill yes)
				)
			)
		)
		(pad "2" smd custom
			(at 0 0.4572 90)
			(size 0.1143 0.1143)
			(layers "B.Cu" "B.Mask" "B.Paste")
			(net "GND")
			(options
				(clearance outline)
				(anchor circle)
			)
			(primitives
				(gr_poly
					(pts
						(arc
							(start -0.254 0.1778)
							(mid -0.239121 0.213721)
							(end -0.2032 0.2286)
						)
						(arc
							(start 0.2032 0.2286)
							(mid 0.239121 0.213721)
							(end 0.254 0.1778)
						)
						(arc
							(start 0.254 -0.1778)
							(mid 0.239121 -0.213721)
							(end 0.2032 -0.2286)
						)
						(arc
							(start -0.2032 -0.2286)
							(mid -0.239121 -0.213721)
							(end -0.254 -0.1778)
						)
					)
					(width 0)
					(fill yes)
				)
			)
		)
	)
)
